(kicad_pcb
	(version 20260206)
	(generator "pcbnew")
	(generator_version "10.0")
	(general
		(thickness 1.6)
		(legacy_teardrops no)
	)
	(paper "A4")
	(title_block
		(title "panther-plus-userver — 13130-1b_20150205.brd")
		(comment 1 "Honey Badger (Wiwynn) / footprints 1103-1110 of 1509")
	)
	(layers
		(0 "F.Cu" signal "TOP")
		(4 "In1.Cu" signal "L2")
		(6 "In2.Cu" signal "L3")
		(8 "In3.Cu" signal "L4")
		(10 "In4.Cu" signal "L5")
		(12 "In5.Cu" signal "L6")
		(14 "In6.Cu" signal "L7")
		(16 "In7.Cu" signal "L8")
		(18 "In8.Cu" signal "L9")
		(20 "In9.Cu" signal "L10")
		(22 "In10.Cu" signal "L11")
		(2 "B.Cu" signal "BOTTOM")
		(9 "F.Adhes" user "F.Adhesive")
		(11 "B.Adhes" user "B.Adhesive")
		(13 "F.Paste" user "Package Geometry/Pastemask Top")
		(15 "B.Paste" user "Package Geometry/Pastemask Bottom")
		(5 "F.SilkS" user "Ref Des/Silkscreen Top")
		(7 "B.SilkS" user "Ref Des/Silkscreen Bottom")
		(1 "F.Mask" user "Board Geometry/Soldermask Top")
		(3 "B.Mask" user "Board Geometry/Soldermask Bottom")
		(17 "Dwgs.User" user "User.Drawings")
		(19 "Cmts.User" user "User.Comments")
		(21 "Eco1.User" user "User.Eco1")
		(23 "Eco2.User" user "User.Eco2")
		(25 "Edge.Cuts" user "Board Geometry/Outline")
		(27 "Margin" user)
		(31 "F.CrtYd" user "Package Geometry/Place Bound Top")
		(29 "B.CrtYd" user "Package Geometry/Place Bound Bottom")
		(35 "F.Fab" user "Ref Des/Assembly Top")
		(33 "B.Fab" user "Ref Des/Assembly Bottom")
	)
	(footprint ""
		(layer "B.Cu")
		(at 101.092 -68.326)
		(property "Reference" "PR3"
			(at 0 0 0)
			(layer "B.SilkS")
			(hide yes)
			(effects
				(font
					(size 1.27 1.27)
				)
				(justify mirror)
			)
		)
		(property "Value" "0R2J-2-GP"
			(at -0.064008 -3.993896 0)
			(unlocked yes)
			(layer "B.Fab")
			(hide yes)
			(effects
				(font
					(size 1.016 1.016)
					(thickness 0.1524)
				)
				(justify mirror)
			)
		)
		(property "Device Type" "R402H16"
			(at -0.064008 -5.517896 0)
			(unlocked yes)
			(layer "B.Fab")
			(hide yes)
			(effects
				(font
					(size 1.016 1.016)
					(thickness 0.1524)
				)
				(justify mirror)
			)
		)
		(duplicate_pad_numbers_are_jumpers no)
		(fp_rect
			(start 0.381 0.8382)
			(end -0.381 -0.8382)
			(stroke
				(width 0)
				(type default)
			)
			(fill no)
			(layer "B.CrtYd")
		)
		(fp_rect
			(start 0.381 0.8382)
			(end -0.381 -0.8382)
			(stroke
				(width 0)
				(type default)
			)
			(fill no)
			(layer "B.Fab")
		)
		(pad "1" smd custom
			(at 0 -0.4318 180)
			(size 0.127 0.127)
			(layers "B.Cu" "B.Mask" "B.Paste")
			(net "P1V1")
			(options
				(clearance outline)
				(anchor circle)
			)
			(primitives
				(gr_poly
					(pts
						(arc
							(start -0.2032 0.2794)
							(mid -0.239121 0.264521)
							(end -0.254 0.2286)
						)
						(arc
							(start -0.254 -0.2286)
							(mid -0.239121 -0.264521)
							(end -0.2032 -0.2794)
						)
						(arc
							(start 0.2032 -0.2794)
							(mid 0.239121 -0.264521)
							(end 0.254 -0.2286)
						)
						(arc
							(start 0.254 0.2286)
							(mid 0.239121 0.264521)
							(end 0.2032 0.2794)
						)
					)
					(width 0)
					(fill yes)
				)
			)
		)
		(pad "2" smd custom
			(at 0 0.4318 180)
			(size 0.127 0.127)
			(layers "B.Cu" "B.Mask" "B.Paste")
			(net "VR_P1V1_VFBR")
			(options
				(clearance outline)
				(anchor circle)
			)
			(primitives
				(gr_poly
					(pts
						(arc
							(start -0.2032 0.2794)
							(mid -0.239121 0.264521)
							(end -0.254 0.2286)
						)
						(arc
							(start -0.254 -0.2286)
							(mid -0.239121 -0.264521)
							(end -0.2032 -0.2794)
						)
						(arc
							(start 0.2032 -0.2794)
							(mid 0.239121 -0.264521)
							(end 0.254 -0.2286)
						)
						(arc
							(start 0.254 0.2286)
							(mid 0.239121 0.264521)
							(end 0.2032 0.2794)
						)
					)
					(width 0)
					(fill yes)
				)
			)
		)
	)
	(footprint ""
		(layer "B.Cu")
		(at 90.424 -40.6654 180)
		(property "Reference" "C176"
			(at 0 0 0)
			(layer "B.SilkS")
			(hide yes)
			(effects
				(font
					(size 1.27 1.27)
				)
				(justify mirror)
			)
		)
		(property "Value" "SC1U10V2KX-1GP"
			(at -1.1811 -2.7051 180)
			(unlocked yes)
			(layer "B.Fab")
			(hide yes)
			(effects
				(font
					(size 1.016 1.016)
					(thickness 0.1524)
				)
				(justify mirror)
			)
		)
		(property "Device Type" "C402H22"
			(at -1.1811 -4.2291 180)
			(unlocked yes)
			(layer "B.Fab")
			(hide yes)
			(effects
				(font
					(size 1.016 1.016)
					(thickness 0.1524)
				)
				(justify mirror)
			)
		)
		(duplicate_pad_numbers_are_jumpers no)
		(fp_rect
			(start 0.381 0.7366)
			(end -0.381 -0.7366)
			(stroke
				(width 0)
				(type default)
			)
			(fill no)
			(layer "B.CrtYd")
		)
		(fp_rect
			(start 0.381 0.7366)
			(end -0.381 -0.7366)
			(stroke
				(width 0)
				(type default)
			)
			(fill no)
			(layer "B.Fab")
		)
		(pad "1" smd custom
			(at 0 -0.4572)
			(size 0.1143 0.1143)
			(layers "B.Cu" "B.Mask" "B.Paste")
			(net "P3V3")
			(options
				(clearance outline)
				(anchor circle)
			)
			(primitives
				(gr_poly
					(pts
						(arc
							(start -0.254 0.1778)
							(mid -0.239121 0.213721)
							(end -0.2032 0.2286)
						)
						(arc
							(start 0.2032 0.2286)
							(mid 0.239121 0.213721)
							(end 0.254 0.1778)
						)
						(arc
							(start 0.254 -0.1778)
							(mid 0.239121 -0.213721)
							(end 0.2032 -0.2286)
						)
						(arc
							(start -0.2032 -0.2286)
							(mid -0.239121 -0.213721)
							(end -0.254 -0.1778)
						)
					)
					(width 0)
					(fill yes)
				)
			)
		)
		(pad "2" smd custom
			(at 0 0.4572)
			(size 0.1143 0.1143)
			(layers "B.Cu" "B.Mask" "B.Paste")
			(net "GND")
			(options
				(clearance outline)
				(anchor circle)
			)
			(primitives
				(gr_poly
					(pts
						(arc
							(start -0.254 0.1778)
							(mid -0.239121 0.213721)
							(end -0.2032 0.2286)
						)
						(arc
							(start 0.2032 0.2286)
							(mid 0.239121 0.213721)
							(end 0.254 0.1778)
						)
						(arc
							(start 0.254 -0.1778)
							(mid 0.239121 -0.213721)
							(end 0.2032 -0.2286)
						)
						(arc
							(start -0.2032 -0.2286)
							(mid -0.239121 -0.213721)
							(end -0.254 -0.1778)
						)
					)
					(width 0)
					(fill yes)
				)
			)
		)
	)
	(footprint ""
		(layer "B.Cu")
		(at 110.744 -27.702002)
		(property "Reference" "C237"
			(at 0 0 0)
			(layer "B.SilkS")
			(hide yes)
			(effects
				(font
					(size 1.27 1.27)
				)
				(justify mirror)
			)
		)
		(property "Value" "SC1U10V2KX-1GP"
			(at -1.1811 -2.7051 0)
			(unlocked yes)
			(layer "B.Fab")
			(hide yes)
			(effects
				(font
					(size 1.016 1.016)
					(thickness 0.1524)
				)
				(justify mirror)
			)
		)
		(property "Device Type" "C402H22"
			(at -1.1811 -4.2291 0)
			(unlocked yes)
			(layer "B.Fab")
			(hide yes)
			(effects
				(font
					(size 1.016 1.016)
					(thickness 0.1524)
				)
				(justify mirror)
			)
		)
		(duplicate_pad_numbers_are_jumpers no)
		(fp_rect
			(start 0.381 0.7366)
			(end -0.381 -0.7366)
			(stroke
				(width 0)
				(type default)
			)
			(fill no)
			(layer "B.CrtYd")
		)
		(fp_rect
			(start 0.381 0.7366)
			(end -0.381 -0.7366)
			(stroke
				(width 0)
				(type default)
			)
			(fill no)
			(layer "B.Fab")
		)
		(pad "1" smd custom
			(at 0 -0.4572 180)
			(size 0.1143 0.1143)
			(layers "B.Cu" "B.Mask" "B.Paste")
			(net "PV_VDDR")
			(options
				(clearance outline)
				(anchor circle)
			)
			(primitives
				(gr_poly
					(pts
						(arc
							(start -0.254 0.1778)
							(mid -0.239121 0.213721)
							(end -0.2032 0.2286)
						)
						(arc
							(start 0.2032 0.2286)
							(mid 0.239121 0.213721)
							(end 0.254 0.1778)
						)
						(arc
							(start 0.254 -0.1778)
							(mid 0.239121 -0.213721)
							(end 0.2032 -0.2286)
						)
						(arc
							(start -0.2032 -0.2286)
							(mid -0.239121 -0.213721)
							(end -0.254 -0.1778)
						)
					)
					(width 0)
					(fill yes)
				)
			)
		)
		(pad "2" smd custom
			(at 0 0.4572 180)
			(size 0.1143 0.1143)
			(layers "B.Cu" "B.Mask" "B.Paste")
			(net "GND")
			(options
				(clearance outline)
				(anchor circle)
			)
			(primitives
				(gr_poly
					(pts
						(arc
							(start -0.254 0.1778)
							(mid -0.239121 0.213721)
							(end -0.2032 0.2286)
						)
						(arc
							(start 0.2032 0.2286)
							(mid 0.239121 0.213721)
							(end 0.254 0.1778)
						)
						(arc
							(start 0.254 -0.1778)
							(mid 0.239121 -0.213721)
							(end 0.2032 -0.2286)
						)
						(arc
							(start -0.2032 -0.2286)
							(mid -0.239121 -0.213721)
							(end -0.254 -0.1778)
						)
					)
					(width 0)
					(fill yes)
				)
			)
		)
	)
	(footprint ""
		(layer "B.Cu")
		(at 74.041 -35.941 -90)
		(property "Reference" "R81"
			(at 0 0 90)
			(layer "B.SilkS")
			(hide yes)
			(effects
				(font
					(size 1.27 1.27)
				)
				(justify mirror)
			)
		)
		(property "Value" "1KR2F-3-GP"
			(at -0.064008 -3.993896 270)
			(unlocked yes)
			(layer "B.Fab")
			(hide yes)
			(effects
				(font
					(size 1.016 1.016)
					(thickness 0.1524)
				)
				(justify mirror)
			)
		)
		(property "Device Type" "R402H16"
			(at -0.064008 -5.517896 270)
			(unlocked yes)
			(layer "B.Fab")
			(hide yes)
			(effects
				(font
					(size 1.016 1.016)
					(thickness 0.1524)
				)
				(justify mirror)
			)
		)
		(duplicate_pad_numbers_are_jumpers no)
		(fp_rect
			(start 0.381 0.8382)
			(end -0.381 -0.8382)
			(stroke
				(width 0)
				(type default)
			)
			(fill no)
			(layer "B.CrtYd")
		)
		(fp_rect
			(start 0.381 0.8382)
			(end -0.381 -0.8382)
			(stroke
				(width 0)
				(type default)
			)
			(fill no)
			(layer "B.Fab")
		)
		(pad "1" smd custom
			(at 0 -0.4318 90)
			(size 0.127 0.127)
			(layers "B.Cu" "B.Mask" "B.Paste")
			(net "FLEX_CLK_SE1")
			(options
				(clearance outline)
				(anchor circle)
			)
			(primitives
				(gr_poly
					(pts
						(arc
							(start -0.2032 0.2794)
							(mid -0.239121 0.264521)
							(end -0.254 0.2286)
						)
						(arc
							(start -0.254 -0.2286)
							(mid -0.239121 -0.264521)
							(end -0.2032 -0.2794)
						)
						(arc
							(start 0.2032 -0.2794)
							(mid 0.239121 -0.264521)
							(end 0.254 -0.2286)
						)
						(arc
							(start 0.254 0.2286)
							(mid 0.239121 0.264521)
							(end 0.2032 0.2794)
						)
					)
					(width 0)
					(fill yes)
				)
			)
		)
		(pad "2" smd custom
			(at 0 0.4318 90)
			(size 0.127 0.127)
			(layers "B.Cu" "B.Mask" "B.Paste")
			(net "GND")
			(options
				(clearance outline)
				(anchor circle)
			)
			(primitives
				(gr_poly
					(pts
						(arc
							(start -0.2032 0.2794)
							(mid -0.239121 0.264521)
							(end -0.254 0.2286)
						)
						(arc
							(start -0.254 -0.2286)
							(mid -0.239121 -0.264521)
							(end -0.2032 -0.2794)
						)
						(arc
							(start 0.2032 -0.2794)
							(mid 0.239121 -0.264521)
							(end 0.254 -0.2286)
						)
						(arc
							(start 0.254 0.2286)
							(mid 0.239121 0.264521)
							(end 0.2032 0.2794)
						)
					)
					(width 0)
					(fill yes)
				)
			)
		)
	)
	(footprint ""
		(layer "B.Cu")
		(at 5.6642 -38.0238 -90)
		(property "Reference" "PC186"
			(at 0 0 90)
			(layer "B.SilkS")
			(hide yes)
			(effects
				(font
					(size 1.27 1.27)
				)
				(justify mirror)
			)
		)
		(property "Value" "SC22U25V5MX-GP"
			(at 0 -4.9022 270)
			(unlocked yes)
			(layer "B.Fab")
			(hide yes)
			(effects
				(font
					(size 1.016 1.016)
					(thickness 0.1524)
				)
				(justify mirror)
			)
		)
		(property "Device Type" "C805H58"
			(at 0 -6.8072 270)
			(unlocked yes)
			(layer "B.Fab")
			(hide yes)
			(effects
				(font
					(size 1.016 1.016)
					(thickness 0.1524)
				)
				(justify mirror)
			)
		)
		(duplicate_pad_numbers_are_jumpers no)
		(fp_line
			(start -0.6096 0)
			(end 0.6096 0)
			(stroke
				(width 0.3048)
				(type default)
			)
			(layer "B.SilkS")
		)
		(fp_poly
			(pts
				(xy 0.9017 1.4351) (xy -0.9017 1.4351) (xy -0.9017 -1.4351) (xy 0.9017 -1.4351)
			)
			(stroke
				(width 0)
				(type default)
			)
			(fill no)
			(layer "B.CrtYd")
		)
		(fp_poly
			(pts
				(xy -0.9017 1.4351) (xy -0.9017 -1.4351) (xy 0.9017 -1.4351) (xy 0.9017 1.4351)
			)
			(stroke
				(width 0)
				(type default)
			)
			(fill no)
			(layer "B.Fab")
		)
		(pad "1" smd rect
			(at 0 -0.8382 90)
			(size 1.5494 0.9398)
			(layers "B.Cu" "B.Mask" "B.Paste")
			(net "P3V3_STBY_VIN")
		)
		(pad "2" smd rect
			(at 0 0.8382 90)
			(size 1.5494 0.9398)
			(layers "B.Cu" "B.Mask" "B.Paste")
			(net "GND")
		)
	)
	(footprint ""
		(layer "B.Cu")
		(at 78.613 -38.4302 90)
		(property "Reference" "R330"
			(at 0 0 90)
			(layer "B.SilkS")
			(hide yes)
			(effects
				(font
					(size 1.27 1.27)
				)
				(justify mirror)
			)
		)
		(property "Value" "22R2F-1-GP"
			(at -0.064008 -3.993896 90)
			(unlocked yes)
			(layer "B.Fab")
			(hide yes)
			(effects
				(font
					(size 1.016 1.016)
					(thickness 0.1524)
				)
				(justify mirror)
			)
		)
		(property "Device Type" "R402H16"
			(at -0.064008 -5.517896 90)
			(unlocked yes)
			(layer "B.Fab")
			(hide yes)
			(effects
				(font
					(size 1.016 1.016)
					(thickness 0.1524)
				)
				(justify mirror)
			)
		)
		(duplicate_pad_numbers_are_jumpers no)
		(fp_rect
			(start 0.381 0.8382)
			(end -0.381 -0.8382)
			(stroke
				(width 0)
				(type default)
			)
			(fill no)
			(layer "B.CrtYd")
		)
		(fp_rect
			(start 0.381 0.8382)
			(end -0.381 -0.8382)
			(stroke
				(width 0)
				(type default)
			)
			(fill no)
			(layer "B.Fab")
		)
		(pad "1" smd custom
			(at 0 -0.4318 270)
			(size 0.127 0.127)
			(layers "B.Cu" "B.Mask" "B.Paste")
			(net "PMU_PLTRST#")
			(options
				(clearance outline)
				(anchor circle)
			)
			(primitives
				(gr_poly
					(pts
						(arc
							(start -0.2032 0.2794)
							(mid -0.239121 0.264521)
							(end -0.254 0.2286)
						)
						(arc
							(start -0.254 -0.2286)
							(mid -0.239121 -0.264521)
							(end -0.2032 -0.2794)
						)
						(arc
							(start 0.2032 -0.2794)
							(mid 0.239121 -0.264521)
							(end 0.254 -0.2286)
						)
						(arc
							(start 0.254 0.2286)
							(mid 0.239121 0.264521)
							(end 0.2032 0.2794)
						)
					)
					(width 0)
					(fill yes)
				)
			)
		)
		(pad "2" smd custom
			(at 0 0.4318 270)
			(size 0.127 0.127)
			(layers "B.Cu" "B.Mask" "B.Paste")
			(net "PMU_PLTRST_R#")
			(options
				(clearance outline)
				(anchor circle)
			)
			(primitives
				(gr_poly
					(pts
						(arc
							(start -0.2032 0.2794)
							(mid -0.239121 0.264521)
							(end -0.254 0.2286)
						)
						(arc
							(start -0.254 -0.2286)
							(mid -0.239121 -0.264521)
							(end -0.2032 -0.2794)
						)
						(arc
							(start 0.2032 -0.2794)
							(mid 0.239121 -0.264521)
							(end 0.254 -0.2286)
						)
						(arc
							(start 0.254 0.2286)
							(mid 0.239121 0.264521)
							(end 0.2032 0.2794)
						)
					)
					(width 0)
					(fill yes)
				)
			)
		)
	)
	(footprint ""
		(layer "B.Cu")
		(at 45.3644 -28.321)
		(property "Reference" "R437"
			(at 0 0 0)
			(layer "B.SilkS")
			(hide yes)
			(effects
				(font
					(size 1.27 1.27)
				)
				(justify mirror)
			)
		)
		(property "Value" "4K7R2F-GP"
			(at -1.7907 -1.1176 0)
			(unlocked yes)
			(layer "B.Fab")
			(hide yes)
			(effects
				(font
					(size 1.016 1.016)
					(thickness 0.1524)
				)
				(justify mirror)
			)
		)
		(property "Device Type" "R402H16"
			(at -1.7907 -2.6416 0)
			(unlocked yes)
			(layer "B.Fab")
			(hide yes)
			(effects
				(font
					(size 1.016 1.016)
					(thickness 0.1524)
				)
				(justify mirror)
			)
		)
		(duplicate_pad_numbers_are_jumpers no)
		(fp_rect
			(start 0.381 0.8382)
			(end -0.381 -0.8382)
			(stroke
				(width 0)
				(type default)
			)
			(fill no)
			(layer "B.CrtYd")
		)
		(fp_rect
			(start 0.381 0.8382)
			(end -0.381 -0.8382)
			(stroke
				(width 0)
				(type default)
			)
			(fill no)
			(layer "B.Fab")
		)
		(pad "1" smd custom
			(at 0 -0.4318 180)
			(size 0.127 0.127)
			(layers "B.Cu" "B.Mask" "B.Paste")
			(net "P3V3")
			(options
				(clearance outline)
				(anchor circle)
			)
			(primitives
				(gr_poly
					(pts
						(arc
							(start -0.2032 0.2794)
							(mid -0.239121 0.264521)
							(end -0.254 0.2286)
						)
						(arc
							(start -0.254 -0.2286)
							(mid -0.239121 -0.264521)
							(end -0.2032 -0.2794)
						)
						(arc
							(start 0.2032 -0.2794)
							(mid 0.239121 -0.264521)
							(end 0.254 -0.2286)
						)
						(arc
							(start 0.254 0.2286)
							(mid 0.239121 0.264521)
							(end 0.2032 0.2794)
						)
					)
					(width 0)
					(fill yes)
				)
			)
		)
		(pad "2" smd custom
			(at 0 0.4318 180)
			(size 0.127 0.127)
			(layers "B.Cu" "B.Mask" "B.Paste")
			(net "CLKBUFF_OE5#")
			(options
				(clearance outline)
				(anchor circle)
			)
			(primitives
				(gr_poly
					(pts
						(arc
							(start -0.2032 0.2794)
							(mid -0.239121 0.264521)
							(end -0.254 0.2286)
						)
						(arc
							(start -0.254 -0.2286)
							(mid -0.239121 -0.264521)
							(end -0.2032 -0.2794)
						)
						(arc
							(start 0.2032 -0.2794)
							(mid 0.239121 -0.264521)
							(end 0.254 -0.2286)
						)
						(arc
							(start 0.254 0.2286)
							(mid 0.239121 0.264521)
							(end 0.2032 0.2794)
						)
					)
					(width 0)
					(fill yes)
				)
			)
		)
	)
	(footprint ""
		(layer "B.Cu")
		(at 20.955 -12.7)
		(property "Reference" "C286"
			(at 0 0 0)
			(layer "B.SilkS")
			(hide yes)
			(effects
				(font
					(size 1.27 1.27)
				)
				(justify mirror)
			)
		)
		(property "Value" "SCD1U16V2KX-3GP"
			(at -1.1811 -2.7051 0)
			(unlocked yes)
			(layer "B.Fab")
			(hide yes)
			(effects
				(font
					(size 1.016 1.016)
					(thickness 0.1524)
				)
				(justify mirror)
			)
		)
		(property "Device Type" "C402H22"
			(at -1.1811 -4.2291 0)
			(unlocked yes)
			(layer "B.Fab")
			(hide yes)
			(effects
				(font
					(size 1.016 1.016)
					(thickness 0.1524)
				)
				(justify mirror)
			)
		)
		(duplicate_pad_numbers_are_jumpers no)
		(fp_rect
			(start 0.381 0.7366)
			(end -0.381 -0.7366)
			(stroke
				(width 0)
				(type default)
			)
			(fill no)
			(layer "B.CrtYd")
		)
		(fp_rect
			(start 0.381 0.7366)
			(end -0.381 -0.7366)
			(stroke
				(width 0)
				(type default)
			)
			(fill no)
			(layer "B.Fab")
		)
		(pad "1" smd custom
			(at 0 -0.4572 180)
			(size 0.1143 0.1143)
			(layers "B.Cu" "B.Mask" "B.Paste")
			(net "P2E_CPU_ETH10G_C_TX_DP11")
			(options
				(clearance outline)
				(anchor circle)
			)
			(primitives
				(gr_poly
					(pts
						(arc
							(start -0.254 0.1778)
							(mid -0.239121 0.213721)
							(end -0.2032 0.2286)
						)
						(arc
							(start 0.2032 0.2286)
							(mid 0.239121 0.213721)
							(end 0.254 0.1778)
						)
						(arc
							(start 0.254 -0.1778)
							(mid 0.239121 -0.213721)
							(end 0.2032 -0.2286)
						)
						(arc
							(start -0.2032 -0.2286)
							(mid -0.239121 -0.213721)
							(end -0.254 -0.1778)
						)
					)
					(width 0)
					(fill yes)
				)
			)
		)
		(pad "2" smd custom
			(at 0 0.4572 180)
			(size 0.1143 0.1143)
			(layers "B.Cu" "B.Mask" "B.Paste")
			(net "P2E_CPU_ETH10G_TX_DP11")
			(options
				(clearance outline)
				(anchor circle)
			)
			(primitives
				(gr_poly
					(pts
						(arc
							(start -0.254 0.1778)
							(mid -0.239121 0.213721)
							(end -0.2032 0.2286)
						)
						(arc
							(start 0.2032 0.2286)
							(mid 0.239121 0.213721)
							(end 0.254 0.1778)
						)
						(arc
							(start 0.254 -0.1778)
							(mid 0.239121 -0.213721)
							(end 0.2032 -0.2286)
						)
						(arc
							(start -0.2032 -0.2286)
							(mid -0.239121 -0.213721)
							(end -0.254 -0.1778)
						)
					)
					(width 0)
					(fill yes)
				)
			)
		)
	)
)
